(kicad_pcb
	(version 20260206)
	(generator "pcbnew")
	(generator_version "10.0")
	(general
		(thickness 1.6)
		(legacy_teardrops no)
	)
	(paper "A4")
	(title_block
		(title "panther-plus-userver — 13130-1b_20150205.brd")
		(comment 1 "Honey Badger (Wiwynn) / footprint 624 of 1509 (DIMM4), pads 198-204 of 210")
	)
	(layers
		(0 "F.Cu" signal "TOP")
		(4 "In1.Cu" signal "L2")
		(6 "In2.Cu" signal "L3")
		(8 "In3.Cu" signal "L4")
		(10 "In4.Cu" signal "L5")
		(12 "In5.Cu" signal "L6")
		(14 "In6.Cu" signal "L7")
		(16 "In7.Cu" signal "L8")
		(18 "In8.Cu" signal "L9")
		(20 "In9.Cu" signal "L10")
		(22 "In10.Cu" signal "L11")
		(2 "B.Cu" signal "BOTTOM")
		(9 "F.Adhes" user "F.Adhesive")
		(11 "B.Adhes" user "B.Adhesive")
		(13 "F.Paste" user "Package Geometry/Pastemask Top")
		(15 "B.Paste" user "Package Geometry/Pastemask Bottom")
		(5 "F.SilkS" user "Ref Des/Silkscreen Top")
		(7 "B.SilkS" user "Ref Des/Silkscreen Bottom")
		(1 "F.Mask" user "Board Geometry/Soldermask Top")
		(3 "B.Mask" user "Board Geometry/Soldermask Bottom")
		(17 "Dwgs.User" user "User.Drawings")
		(19 "Cmts.User" user "User.Comments")
		(21 "Eco1.User" user "User.Eco1")
		(23 "Eco2.User" user "User.Eco2")
		(25 "Edge.Cuts" user "Board Geometry/Outline")
		(27 "Margin" user)
		(31 "F.CrtYd" user "Package Geometry/Place Bound Top")
		(29 "B.CrtYd" user "Package Geometry/Place Bound Bottom")
		(35 "F.Fab" user "Ref Des/Assembly Top")
		(33 "B.Fab" user "Ref Des/Assembly Bottom")
	)
	(footprint ""
		(layer "F.Cu")
		(at 159.999934 -5.790692)
		(property "Reference" "DIMM4"
			(at 0 0 0)
			(layer "F.SilkS")
			(hide yes)
			(effects
				(font
					(size 1.27 1.27)
				)
			)
		)
		(property "Value" "DDR3-204P-174-COLAY-1-GP"
			(at -40.682164 -17.468088 0)
			(unlocked yes)
			(layer "F.Fab")
			(hide yes)
			(effects
				(font
					(size 1.016 1.016)
					(thickness 0.1524)
				)
			)
		)
		(property "Device Type" "AS0A626-H8SN-7H-COLAY-1"
			(at -40.682164 -18.992088 0)
			(unlocked yes)
			(layer "F.Fab")
			(hide yes)
			(effects
				(font
					(size 1.016 1.016)
					(thickness 0.1524)
				)
			)
		)
		(duplicate_pad_numbers_are_jumpers no)
		(pad "196" smd custom
			(at 29.249878 -4.106672)
			(size 0.1143 0.1143)
			(layers "F.Cu" "F.Mask" "F.Paste")
			(net "GND")
			(options
				(clearance outline)
				(anchor circle)
			)
			(primitives
				(gr_poly
					(pts
						(xy 0 0.9017) (xy -0.03175 0.89916) (xy -0.0635 0.889) (xy -0.09144 0.87376) (xy -0.11684 0.85344)
						(xy -0.13716 0.82804) (xy -0.1524 0.8001) (xy -0.16256 0.76835) (xy -0.1651 0.7366) (xy -0.1651 0.19685)
						(xy -0.17272 0.18923) (xy -0.17907 0.18034) (xy -0.18669 0.17145) (xy -0.19177 0.16256) (xy -0.19812 0.15367)
						(xy -0.20828 0.13335) (xy -0.21971 0.10287) (xy -0.22225 0.09271) (xy -0.22479 0.08128) (xy -0.22606 0.07112)
						(xy -0.2286 0.05969) (xy -0.2286 0.01651) (xy -0.22606 0.00508) (xy -0.22479 -0.00508) (xy -0.22225 -0.01651)
						(xy -0.21971 -0.02667) (xy -0.20828 -0.05715) (xy -0.19812 -0.07747) (xy -0.19177 -0.08636) (xy -0.18669 -0.09525)
						(xy -0.17907 -0.10414) (xy -0.17272 -0.11303) (xy -0.1651 -0.12065) (xy -0.1651 -0.7366) (xy -0.16256 -0.76835)
						(xy -0.1524 -0.8001) (xy -0.13716 -0.82804) (xy -0.11684 -0.85344) (xy -0.09144 -0.87376) (xy -0.0635 -0.889)
						(xy -0.03175 -0.89916) (xy 0 -0.9017) (xy 0.03175 -0.89916) (xy 0.0635 -0.889) (xy 0.09144 -0.87376)
						(xy 0.11684 -0.85344) (xy 0.13716 -0.82804) (xy 0.1524 -0.8001) (xy 0.16256 -0.76835) (xy 0.1651 -0.7366)
						(xy 0.1651 -0.11938) (xy 0.17272 -0.11176) (xy 0.19812 -0.0762) (xy 0.2032 -0.06604) (xy 0.20701 -0.05715)
						(xy 0.21209 -0.04699) (xy 0.2159 -0.03683) (xy 0.21844 -0.02667) (xy 0.22225 -0.01524) (xy 0.22352 -0.00508)
						(xy 0.22606 0.00508) (xy 0.22733 0.01651) (xy 0.22733 0.02667) (xy 0.2286 0.0381) (xy 0.22733 0.04953)
						(xy 0.22733 0.05969) (xy 0.22606 0.07112) (xy 0.22352 0.08128) (xy 0.22225 0.09144) (xy 0.21844 0.10287)
						(xy 0.2159 0.11303) (xy 0.21209 0.12319) (xy 0.20701 0.13335) (xy 0.2032 0.14224) (xy 0.19812 0.1524)
						(xy 0.17272 0.18796) (xy 0.1651 0.19558) (xy 0.1651 0.7366) (xy 0.16256 0.76835) (xy 0.1524 0.8001)
						(xy 0.13716 0.82804) (xy 0.11684 0.85344) (xy 0.09144 0.87376) (xy 0.0635 0.889) (xy 0.03175 0.89916)
					)
					(width 0)
					(fill yes)
				)
			)
		)
		(pad "197" smd custom
			(at 29.550106 4.106672)
			(size 0.1143 0.1143)
			(layers "F.Cu" "F.Mask" "F.Paste")
			(net "CHB_1_SA0")
			(options
				(clearance outline)
				(anchor circle)
			)
			(primitives
				(gr_poly
					(pts
						(xy 0 0.9017) (xy -0.03175 0.89916) (xy -0.0635 0.889) (xy -0.09144 0.87376) (xy -0.11684 0.85344)
						(xy -0.13716 0.82804) (xy -0.1524 0.8001) (xy -0.16256 0.76835) (xy -0.1651 0.7366) (xy -0.1651 -0.13462)
						(xy -0.17272 -0.14224) (xy -0.19812 -0.1778) (xy -0.2032 -0.18796) (xy -0.20701 -0.19685) (xy -0.21209 -0.20701)
						(xy -0.2159 -0.21717) (xy -0.21844 -0.22733) (xy -0.22225 -0.23876) (xy -0.22352 -0.24892) (xy -0.22606 -0.25908)
						(xy -0.22733 -0.27051) (xy -0.22733 -0.28067) (xy -0.2286 -0.2921) (xy -0.22733 -0.30353) (xy -0.22733 -0.31369)
						(xy -0.22606 -0.32512) (xy -0.22352 -0.33528) (xy -0.22225 -0.34544) (xy -0.21844 -0.35687) (xy -0.2159 -0.36703)
						(xy -0.21209 -0.37719) (xy -0.20701 -0.38735) (xy -0.2032 -0.39624) (xy -0.19812 -0.4064) (xy -0.17272 -0.44196)
						(xy -0.1651 -0.44958) (xy -0.1651 -0.7366) (xy -0.16256 -0.76835) (xy -0.1524 -0.8001) (xy -0.13716 -0.82804)
						(xy -0.11684 -0.85344) (xy -0.09144 -0.87376) (xy -0.0635 -0.889) (xy -0.03175 -0.89916) (xy 0 -0.9017)
						(xy 0.03175 -0.89916) (xy 0.0635 -0.889) (xy 0.09144 -0.87376) (xy 0.11684 -0.85344) (xy 0.13716 -0.82804)
						(xy 0.1524 -0.8001) (xy 0.16256 -0.76835) (xy 0.1651 -0.7366) (xy 0.1651 -0.44958) (xy 0.17272 -0.44196)
						(xy 0.19812 -0.4064) (xy 0.2032 -0.39624) (xy 0.20701 -0.38735) (xy 0.21209 -0.37719) (xy 0.2159 -0.36703)
						(xy 0.21844 -0.35687) (xy 0.22225 -0.34544) (xy 0.22352 -0.33528) (xy 0.22606 -0.32512) (xy 0.22733 -0.31369)
						(xy 0.22733 -0.30353) (xy 0.2286 -0.2921) (xy 0.22733 -0.28067) (xy 0.22733 -0.27051) (xy 0.22606 -0.25908)
						(xy 0.22352 -0.24892) (xy 0.22225 -0.23876) (xy 0.21844 -0.22733) (xy 0.2159 -0.21717) (xy 0.21209 -0.20701)
						(xy 0.20701 -0.19685) (xy 0.2032 -0.18796) (xy 0.19812 -0.1778) (xy 0.17272 -0.14224) (xy 0.1651 -0.13462)
						(xy 0.1651 0.7366) (xy 0.16256 0.76835) (xy 0.1524 0.8001) (xy 0.13716 0.82804) (xy 0.11684 0.85344)
						(xy 0.09144 0.87376) (xy 0.0635 0.889) (xy 0.03175 0.89916)
					)
					(width 0)
					(fill yes)
				)
			)
		)
		(pad "198" smd custom
			(at 29.85008 -4.106672)
			(size 0.1143 0.1143)
			(layers "F.Cu" "F.Mask" "F.Paste")
			(net "MEMORY_HOT_LV_R#")
			(options
				(clearance outline)
				(anchor circle)
			)
			(primitives
				(gr_poly
					(pts
						(xy 0 0.9017) (xy -0.03175 0.89916) (xy -0.0635 0.889) (xy -0.09144 0.87376) (xy -0.11684 0.85344)
						(xy -0.13716 0.82804) (xy -0.1524 0.8001) (xy -0.16256 0.76835) (xy -0.1651 0.7366) (xy -0.1651 0.44958)
						(xy -0.17272 0.44196) (xy -0.19812 0.4064) (xy -0.2032 0.39624) (xy -0.20701 0.38735) (xy -0.21209 0.37719)
						(xy -0.2159 0.36703) (xy -0.21844 0.35687) (xy -0.22225 0.34544) (xy -0.22352 0.33528) (xy -0.22606 0.32512)
						(xy -0.22733 0.31369) (xy -0.22733 0.30353) (xy -0.2286 0.2921) (xy -0.22733 0.28067) (xy -0.22733 0.27051)
						(xy -0.22606 0.25908) (xy -0.22352 0.24892) (xy -0.22225 0.23876) (xy -0.21844 0.22733) (xy -0.2159 0.21717)
						(xy -0.21209 0.20701) (xy -0.20701 0.19685) (xy -0.2032 0.18796) (xy -0.19812 0.1778) (xy -0.17272 0.14224)
						(xy -0.1651 0.13462) (xy -0.1651 -0.7366) (xy -0.16256 -0.76835) (xy -0.1524 -0.8001) (xy -0.13716 -0.82804)
						(xy -0.11684 -0.85344) (xy -0.09144 -0.87376) (xy -0.0635 -0.889) (xy -0.03175 -0.89916) (xy 0 -0.9017)
						(xy 0.03175 -0.89916) (xy 0.0635 -0.889) (xy 0.09144 -0.87376) (xy 0.11684 -0.85344) (xy 0.13716 -0.82804)
						(xy 0.1524 -0.8001) (xy 0.16256 -0.76835) (xy 0.1651 -0.7366) (xy 0.1651 0.13462) (xy 0.17272 0.14224)
						(xy 0.19812 0.1778) (xy 0.2032 0.18796) (xy 0.20701 0.19685) (xy 0.21209 0.20701) (xy 0.2159 0.21717)
						(xy 0.21844 0.22733) (xy 0.22225 0.23876) (xy 0.22352 0.24892) (xy 0.22606 0.25908) (xy 0.22733 0.27051)
						(xy 0.22733 0.28067) (xy 0.2286 0.2921) (xy 0.22733 0.30353) (xy 0.22733 0.31369) (xy 0.22606 0.32512)
						(xy 0.22352 0.33528) (xy 0.22225 0.34544) (xy 0.21844 0.35687) (xy 0.2159 0.36703) (xy 0.21209 0.37719)
						(xy 0.20701 0.38735) (xy 0.2032 0.39624) (xy 0.19812 0.4064) (xy 0.17272 0.44196) (xy 0.1651 0.44958)
						(xy 0.1651 0.7366) (xy 0.16256 0.76835) (xy 0.1524 0.8001) (xy 0.13716 0.82804) (xy 0.11684 0.85344)
						(xy 0.09144 0.87376) (xy 0.0635 0.889) (xy 0.03175 0.89916)
					)
					(width 0)
					(fill yes)
				)
			)
		)
		(pad "199" smd custom
			(at 30.150054 4.106672)
			(size 0.1143 0.1143)
			(layers "F.Cu" "F.Mask" "F.Paste")
			(net "P3V3_STBY")
			(options
				(clearance outline)
				(anchor circle)
			)
			(primitives
				(gr_poly
					(pts
						(xy 0 0.9017) (xy -0.03175 0.89916) (xy -0.0635 0.889) (xy -0.09144 0.87376) (xy -0.11684 0.85344)
						(xy -0.13716 0.82804) (xy -0.1524 0.8001) (xy -0.16256 0.76835) (xy -0.1651 0.7366) (xy -0.1651 0.11938)
						(xy -0.17272 0.11176) (xy -0.19812 0.0762) (xy -0.2032 0.06604) (xy -0.20701 0.05715) (xy -0.21209 0.04699)
						(xy -0.2159 0.03683) (xy -0.21844 0.02667) (xy -0.22225 0.01524) (xy -0.22352 0.00508) (xy -0.22606 -0.00508)
						(xy -0.22733 -0.01651) (xy -0.22733 -0.02667) (xy -0.2286 -0.0381) (xy -0.22733 -0.04953) (xy -0.22733 -0.05969)
						(xy -0.22606 -0.07112) (xy -0.22352 -0.08128) (xy -0.22225 -0.09144) (xy -0.21844 -0.10287) (xy -0.2159 -0.11303)
						(xy -0.21209 -0.12319) (xy -0.20701 -0.13335) (xy -0.2032 -0.14224) (xy -0.19812 -0.1524) (xy -0.17272 -0.18796)
						(xy -0.1651 -0.19558) (xy -0.1651 -0.7366) (xy -0.16256 -0.76835) (xy -0.1524 -0.8001) (xy -0.13716 -0.82804)
						(xy -0.11684 -0.85344) (xy -0.09144 -0.87376) (xy -0.0635 -0.889) (xy -0.03175 -0.89916) (xy 0 -0.9017)
						(xy 0.03175 -0.89916) (xy 0.0635 -0.889) (xy 0.09144 -0.87376) (xy 0.11684 -0.85344) (xy 0.13716 -0.82804)
						(xy 0.1524 -0.8001) (xy 0.16256 -0.76835) (xy 0.1651 -0.7366) (xy 0.1651 -0.19685) (xy 0.17272 -0.18923)
						(xy 0.17907 -0.18034) (xy 0.18669 -0.17145) (xy 0.19177 -0.16256) (xy 0.19812 -0.15367) (xy 0.20828 -0.13335)
						(xy 0.21971 -0.10287) (xy 0.22225 -0.09271) (xy 0.22479 -0.08128) (xy 0.22606 -0.07112) (xy 0.2286 -0.05969)
						(xy 0.2286 -0.01651) (xy 0.22606 -0.00508) (xy 0.22479 0.00508) (xy 0.22225 0.01651) (xy 0.21971 0.02667)
						(xy 0.20828 0.05715) (xy 0.19812 0.07747) (xy 0.19177 0.08636) (xy 0.18669 0.09525) (xy 0.17907 0.10414)
						(xy 0.17272 0.11303) (xy 0.1651 0.12065) (xy 0.1651 0.7366) (xy 0.16256 0.76835) (xy 0.1524 0.8001)
						(xy 0.13716 0.82804) (xy 0.11684 0.85344) (xy 0.09144 0.87376) (xy 0.0635 0.889) (xy 0.03175 0.89916)
					)
					(width 0)
					(fill yes)
				)
			)
		)
		(pad "200" smd custom
			(at 30.450028 -4.106672)
			(size 0.1143 0.1143)
			(layers "F.Cu" "F.Mask" "F.Paste")
			(net "SMB_M_B1_R_DATA")
			(options
				(clearance outline)
				(anchor circle)
			)
			(primitives
				(gr_poly
					(pts
						(xy 0 0.9017) (xy -0.03175 0.89916) (xy -0.0635 0.889) (xy -0.09144 0.87376) (xy -0.11684 0.85344)
						(xy -0.13716 0.82804) (xy -0.1524 0.8001) (xy -0.16256 0.76835) (xy -0.1651 0.7366) (xy -0.1651 0.19685)
						(xy -0.17272 0.18923) (xy -0.17907 0.18034) (xy -0.18669 0.17145) (xy -0.19177 0.16256) (xy -0.19812 0.15367)
						(xy -0.20828 0.13335) (xy -0.21971 0.10287) (xy -0.22225 0.09271) (xy -0.22479 0.08128) (xy -0.22606 0.07112)
						(xy -0.2286 0.05969) (xy -0.2286 0.01651) (xy -0.22606 0.00508) (xy -0.22479 -0.00508) (xy -0.22225 -0.01651)
						(xy -0.21971 -0.02667) (xy -0.20828 -0.05715) (xy -0.19812 -0.07747) (xy -0.19177 -0.08636) (xy -0.18669 -0.09525)
						(xy -0.17907 -0.10414) (xy -0.17272 -0.11303) (xy -0.1651 -0.12065) (xy -0.1651 -0.7366) (xy -0.16256 -0.76835)
						(xy -0.1524 -0.8001) (xy -0.13716 -0.82804) (xy -0.11684 -0.85344) (xy -0.09144 -0.87376) (xy -0.0635 -0.889)
						(xy -0.03175 -0.89916) (xy 0 -0.9017) (xy 0.03175 -0.89916) (xy 0.0635 -0.889) (xy 0.09144 -0.87376)
						(xy 0.11684 -0.85344) (xy 0.13716 -0.82804) (xy 0.1524 -0.8001) (xy 0.16256 -0.76835) (xy 0.1651 -0.7366)
						(xy 0.1651 -0.11938) (xy 0.17272 -0.11176) (xy 0.19812 -0.0762) (xy 0.2032 -0.06604) (xy 0.20701 -0.05715)
						(xy 0.21209 -0.04699) (xy 0.2159 -0.03683) (xy 0.21844 -0.02667) (xy 0.22225 -0.01524) (xy 0.22352 -0.00508)
						(xy 0.22606 0.00508) (xy 0.22733 0.01651) (xy 0.22733 0.02667) (xy 0.2286 0.0381) (xy 0.22733 0.04953)
						(xy 0.22733 0.05969) (xy 0.22606 0.07112) (xy 0.22352 0.08128) (xy 0.22225 0.09144) (xy 0.21844 0.10287)
						(xy 0.2159 0.11303) (xy 0.21209 0.12319) (xy 0.20701 0.13335) (xy 0.2032 0.14224) (xy 0.19812 0.1524)
						(xy 0.17272 0.18796) (xy 0.1651 0.19558) (xy 0.1651 0.7366) (xy 0.16256 0.76835) (xy 0.1524 0.8001)
						(xy 0.13716 0.82804) (xy 0.11684 0.85344) (xy 0.09144 0.87376) (xy 0.0635 0.889) (xy 0.03175 0.89916)
					)
					(width 0)
					(fill yes)
				)
			)
		)
		(pad "201" smd custom
			(at 30.750002 4.106672)
			(size 0.1143 0.1143)
			(layers "F.Cu" "F.Mask" "F.Paste")
			(net "CHB_1_SA1")
			(options
				(clearance outline)
				(anchor circle)
			)
			(primitives
				(gr_poly
					(pts
						(xy 0 0.9017) (xy -0.03175 0.89916) (xy -0.0635 0.889) (xy -0.09144 0.87376) (xy -0.11684 0.85344)
						(xy -0.13716 0.82804) (xy -0.1524 0.8001) (xy -0.16256 0.76835) (xy -0.1651 0.7366) (xy -0.1651 -0.13462)
						(xy -0.17272 -0.14224) (xy -0.19812 -0.1778) (xy -0.2032 -0.18796) (xy -0.20701 -0.19685) (xy -0.21209 -0.20701)
						(xy -0.2159 -0.21717) (xy -0.21844 -0.22733) (xy -0.22225 -0.23876) (xy -0.22352 -0.24892) (xy -0.22606 -0.25908)
						(xy -0.22733 -0.27051) (xy -0.22733 -0.28067) (xy -0.2286 -0.2921) (xy -0.22733 -0.30353) (xy -0.22733 -0.31369)
						(xy -0.22606 -0.32512) (xy -0.22352 -0.33528) (xy -0.22225 -0.34544) (xy -0.21844 -0.35687) (xy -0.2159 -0.36703)
						(xy -0.21209 -0.37719) (xy -0.20701 -0.38735) (xy -0.2032 -0.39624) (xy -0.19812 -0.4064) (xy -0.17272 -0.44196)
						(xy -0.1651 -0.44958) (xy -0.1651 -0.7366) (xy -0.16256 -0.76835) (xy -0.1524 -0.8001) (xy -0.13716 -0.82804)
						(xy -0.11684 -0.85344) (xy -0.09144 -0.87376) (xy -0.0635 -0.889) (xy -0.03175 -0.89916) (xy 0 -0.9017)
						(xy 0.03175 -0.89916) (xy 0.0635 -0.889) (xy 0.09144 -0.87376) (xy 0.11684 -0.85344) (xy 0.13716 -0.82804)
						(xy 0.1524 -0.8001) (xy 0.16256 -0.76835) (xy 0.1651 -0.7366) (xy 0.1651 -0.44958) (xy 0.17272 -0.44196)
						(xy 0.19812 -0.4064) (xy 0.2032 -0.39624) (xy 0.20701 -0.38735) (xy 0.21209 -0.37719) (xy 0.2159 -0.36703)
						(xy 0.21844 -0.35687) (xy 0.22225 -0.34544) (xy 0.22352 -0.33528) (xy 0.22606 -0.32512) (xy 0.22733 -0.31369)
						(xy 0.22733 -0.30353) (xy 0.2286 -0.2921) (xy 0.22733 -0.28067) (xy 0.22733 -0.27051) (xy 0.22606 -0.25908)
						(xy 0.22352 -0.24892) (xy 0.22225 -0.23876) (xy 0.21844 -0.22733) (xy 0.2159 -0.21717) (xy 0.21209 -0.20701)
						(xy 0.20701 -0.19685) (xy 0.2032 -0.18796) (xy 0.19812 -0.1778) (xy 0.17272 -0.14224) (xy 0.1651 -0.13462)
						(xy 0.1651 0.7366) (xy 0.16256 0.76835) (xy 0.1524 0.8001) (xy 0.13716 0.82804) (xy 0.11684 0.85344)
						(xy 0.09144 0.87376) (xy 0.0635 0.889) (xy 0.03175 0.89916)
					)
					(width 0)
					(fill yes)
				)
			)
		)
		(pad "202" smd custom
			(at 31.049976 -4.106672)
			(size 0.1143 0.1143)
			(layers "F.Cu" "F.Mask" "F.Paste")
			(net "SMB_M_B1_R_CLK")
			(options
				(clearance outline)
				(anchor circle)
			)
			(primitives
				(gr_poly
					(pts
						(xy 0 0.9017) (xy -0.03175 0.89916) (xy -0.0635 0.889) (xy -0.09144 0.87376) (xy -0.11684 0.85344)
						(xy -0.13716 0.82804) (xy -0.1524 0.8001) (xy -0.16256 0.76835) (xy -0.1651 0.7366) (xy -0.1651 0.44958)
						(xy -0.17272 0.44196) (xy -0.19812 0.4064) (xy -0.2032 0.39624) (xy -0.20701 0.38735) (xy -0.21209 0.37719)
						(xy -0.2159 0.36703) (xy -0.21844 0.35687) (xy -0.22225 0.34544) (xy -0.22352 0.33528) (xy -0.22606 0.32512)
						(xy -0.22733 0.31369) (xy -0.22733 0.30353) (xy -0.2286 0.2921) (xy -0.22733 0.28067) (xy -0.22733 0.27051)
						(xy -0.22606 0.25908) (xy -0.22352 0.24892) (xy -0.22225 0.23876) (xy -0.21844 0.22733) (xy -0.2159 0.21717)
						(xy -0.21209 0.20701) (xy -0.20701 0.19685) (xy -0.2032 0.18796) (xy -0.19812 0.1778) (xy -0.17272 0.14224)
						(xy -0.1651 0.13462) (xy -0.1651 -0.7366) (xy -0.16256 -0.76835) (xy -0.1524 -0.8001) (xy -0.13716 -0.82804)
						(xy -0.11684 -0.85344) (xy -0.09144 -0.87376) (xy -0.0635 -0.889) (xy -0.03175 -0.89916) (xy 0 -0.9017)
						(xy 0.03175 -0.89916) (xy 0.0635 -0.889) (xy 0.09144 -0.87376) (xy 0.11684 -0.85344) (xy 0.13716 -0.82804)
						(xy 0.1524 -0.8001) (xy 0.16256 -0.76835) (xy 0.1651 -0.7366) (xy 0.1651 0.13462) (xy 0.17272 0.14224)
						(xy 0.19812 0.1778) (xy 0.2032 0.18796) (xy 0.20701 0.19685) (xy 0.21209 0.20701) (xy 0.2159 0.21717)
						(xy 0.21844 0.22733) (xy 0.22225 0.23876) (xy 0.22352 0.24892) (xy 0.22606 0.25908) (xy 0.22733 0.27051)
						(xy 0.22733 0.28067) (xy 0.2286 0.2921) (xy 0.22733 0.30353) (xy 0.22733 0.31369) (xy 0.22606 0.32512)
						(xy 0.22352 0.33528) (xy 0.22225 0.34544) (xy 0.21844 0.35687) (xy 0.2159 0.36703) (xy 0.21209 0.37719)
						(xy 0.20701 0.38735) (xy 0.2032 0.39624) (xy 0.19812 0.4064) (xy 0.17272 0.44196) (xy 0.1651 0.44958)
						(xy 0.1651 0.7366) (xy 0.16256 0.76835) (xy 0.1524 0.8001) (xy 0.13716 0.82804) (xy 0.11684 0.85344)
						(xy 0.09144 0.87376) (xy 0.0635 0.889) (xy 0.03175 0.89916)
					)
					(width 0)
					(fill yes)
				)
			)
		)
	)
)
